# T6G (Grand Teton) — schematic netlist excerpt (pin names and nets, part order shuffled) for the footprints in the layout excerpt that follows; sources: Cadence DE-HDL packaged netlist, KiCad conversion of 04192023_DAF0TMB3IC0_F0TG_MB_C_brd_V02_OCP.brd

J1  SCONN288_DDR506112002KQ  IO  pkg DDR288S_1-1VXC  page 86
  VIN_BULK0  = P12V_MEM_CPU0
  RFU0  = NC
  VIN_MGMT  = P3V3_AUX
  HSCL  = I3C_SPD_DDRA_CPU0_SCL
  HSDA  = I3C_SPD_DDRA_CPU0_SDA
  VSS0  = GND
  DQ0_A  = M_A_CPU0_SA_DQ<0>
  VSS1  = GND
  DQ1_A  = M_A_CPU0_SA_DQ<1>
  VSS2  = GND
  DQS0_A_T  = M_A_CPU0_SA_DQS_DP<0>
  DQS0_A_C  = M_A_CPU0_SA_DQS_DN<0>
  VSS3  = GND
  DQ4_A  = M_A_CPU0_SA_DQ<4>
  VSS4  = GND
  DQ5_A  = M_A_CPU0_SA_DQ<5>
  VSS5  = GND
  DQ8_A  = M_A_CPU0_SA_DQ<8>
  VSS6  = GND
  DQ9_A  = M_A_CPU0_SA_DQ<9>
  VSS7  = GND
  DQS1_A_T  = M_A_CPU0_SA_DQS_DP<1>
  DQS1_A_C  = M_A_CPU0_SA_DQS_DN<1>
  VSS8  = GND
  DQ12_A  = M_A_CPU0_SA_DQ<12>
  VSS9  = GND
  DQ13_A  = M_A_CPU0_SA_DQ<13>
  VSS10  = GND
  DQ16_A  = M_A_CPU0_SA_DQ<16>
  VSS11  = GND
  DQ17_A  = M_A_CPU0_SA_DQ<17>
  VSS12  = GND
  DQS2_A_T  = M_A_CPU0_SA_DQS_DP<2>
  DQS2_A_C  = M_A_CPU0_SA_DQS_DN<2>
  VSS13  = GND
  DQ20_A  = M_A_CPU0_SA_DQ<20>
  VSS14  = GND
  DQ21_A  = M_A_CPU0_SA_DQ<21>
  VSS15  = GND
  DQ24_A  = M_A_CPU0_SA_DQ<24>
  VSS16  = GND
  DQ25_A  = M_A_CPU0_SA_DQ<25>
  VSS17  = GND
  DQS3_A_T  = M_A_CPU0_SA_DQS_DP<3>
  DQS3_A_C  = M_A_CPU0_SA_DQS_DN<3>
  VSS18  = GND
  DQ28_A  = M_A_CPU0_SA_DQ<28>
  VSS19  = GND
  DQ29_A  = M_A_CPU0_SA_DQ<29>
  VSS20  = GND
  CB0_A  = M_A_CPU0_SA_CB<0>
  VSS21  = GND
  CB1_A  = M_A_CPU0_SA_CB<1>
  VSS22  = GND
  DQS4_A_T  = M_A_CPU0_SA_DQS_DP<4>
  DQS4_A_C  = M_A_CPU0_SA_DQS_DN<4>
  VSS23  = GND
  CB4_A  = M_A_CPU0_SA_CB<4>
  VSS24  = GND
  CB5_A  = M_A_CPU0_SA_CB<5>
  VSS25  = GND
  ALERT_N  = M_A_CPU0_ALERT_N
  VSS26  = GND
  CS0_A_N  = M_A_CPU0_SA_CS_N<0>
  VSS27  = GND
  CA0_A  = M_A_CPU0_SA_CA<0>
  VSS28  = GND
  CA2_A  = M_A_CPU0_SA_CA<2>
  VSS29  = GND
  CA4_A  = M_A_CPU0_SA_CA<4>
  VSS30  = GND
  CA6_A  = M_A_CPU0_SA_CA<6>
  VSS31  = GND
  PAR_A  = M_A_CPU0_SA_PAR
  VSS32  = GND
  CA0_B  = M_A_CPU0_SB_CA<0>
  VSS33  = GND
  CA2_B  = M_A_CPU0_SB_CA<2>
  VSS34  = GND
  CA4_B  = M_A_CPU0_SB_CA<4>
  VSS35  = GND
  CA6_B  = M_A_CPU0_SB_CA<6>
  VSS36  = GND
  CS0_B_N  = M_A_CPU0_SB_CS_N<0>
  VSS37  = GND
  \lbd||rsp_a_n\  = M_A_CPU0_SA_RSP<0>
  \lbs||rsp_b_n\  = M_A_CPU0_SB_RSP<0>
  VSS38  = GND
  CB4_B  = M_A_CPU0_SB_CB<4>
  VSS39  = GND
  CB5_B  = M_A_CPU0_SB_CB<5>
  VSS40  = GND
  \dqs9_b_t||tdqs9_b_t||dbi4_b_n\  = M_A_CPU0_SB_DQS_DP<9>
  \dqs9_b_c||tdqs9_b_c\  = M_A_CPU0_SB_DQS_DN<9>
  VSS41  = GND
  CB0_B  = M_A_CPU0_SB_CB<0>
  VSS42  = GND
  CB1_B  = M_A_CPU0_SB_CB<1>
  VSS43  = GND
  DQ0_B  = M_A_CPU0_SB_DQ<0>
  VSS44  = GND
  DQ1_B  = M_A_CPU0_SB_DQ<1>
  VSS45  = GND
  DQS0_B_T  = M_A_CPU0_SB_DQS_DP<0>
  DQS0_B_C  = M_A_CPU0_SB_DQS_DN<0>
  VSS46  = GND
  DQ4_B  = M_A_CPU0_SB_DQ<4>
  VSS47  = GND
  DQ5_B  = M_A_CPU0_SB_DQ<5>
  VSS48  = GND
  DQ8_B  = M_A_CPU0_SB_DQ<8>
  VSS49  = GND
  DQ9_B  = M_A_CPU0_SB_DQ<9>
  VSS50  = GND
  DQS1_B_T  = M_A_CPU0_SB_DQS_DP<1>
  DQS1_B_C  = M_A_CPU0_SB_DQS_DN<1>
  VSS51  = GND
  DQ12_B  = M_A_CPU0_SB_DQ<12>
  VSS52  = GND
  DQ13_B  = M_A_CPU0_SB_DQ<13>
  VSS53  = GND
  DQ16_B  = M_A_CPU0_SB_DQ<16>
  VSS54  = GND
  DQ17_B  = M_A_CPU0_SB_DQ<17>
  VSS55  = GND
  DQS2_B_T  = M_A_CPU0_SB_DQS_DP<2>
  DQS2_B_C  = M_A_CPU0_SB_DQS_DN<2>
  VSS56  = GND
  DQ20_B  = M_A_CPU0_SB_DQ<20>
  VSS57  = GND
  DQ21_B  = M_A_CPU0_SB_DQ<21>
  VSS58  = GND
  DQ24_B  = M_A_CPU0_SB_DQ<24>
  VSS59  = GND
  DQ25_B  = M_A_CPU0_SB_DQ<25>
  VSS60  = GND
  DQS3_B_T  = M_A_CPU0_SB_DQS_DP<3>
  DQS3_B_C  = M_A_CPU0_SB_DQS_DN<3>
  VSS61  = GND
  DQ28_B  = M_A_CPU0_SB_DQ<28>
  VSS62  = GND
  DQ29_B  = M_A_CPU0_SB_DQ<29>
  VSS63  = GND
  RFU1  = NC
  VIN_BULK1  = P12V_MEM_CPU0
  VIN_BULK2  = P12V_MEM_CPU0
  \pwr_good||fail_n\  = PWRGD_CHA_CPU0_DIMM0
  HAS  = PD_CHA_CPU0_DIMM0_SAA
  RFU2  = NC
  RFU3  = NC
  VSS64  = GND
  DQ2_A  = M_A_CPU0_SA_DQ<2>
  VSS65  = GND
  DQ3_A  = M_A_CPU0_SA_DQ<3>
  VSS66  = GND
  \dqs5_a_c||tdqs5_a_c||dqs5_a_t||tdqs5_a_t\  = M_A_CPU0_SA_DQS_DN<5>
  \dqs5_a_t||tdqs5_a_t\  = M_A_CPU0_SA_DQS_DP<5>
  VSS67  = GND
  DQ6_A  = M_A_CPU0_SA_DQ<6>
  VSS68  = GND
  DQ7_A  = M_A_CPU0_SA_DQ<7>
  VSS69  = GND
  DQ10_A  = M_A_CPU0_SA_DQ<10>
  VSS70  = GND
  DQ11_A  = M_A_CPU0_SA_DQ<11>
  VSS71  = GND
  \dqs6_a_c||tdqs6_a_c||dqs6_a_t||tdqs6_a_t\  = M_A_CPU0_SA_DQS_DN<6>
  \dqs6_a_t||tdqs6_a_t\  = M_A_CPU0_SA_DQS_DP<6>
  VSS72  = GND
  DQ14_A  = M_A_CPU0_SA_DQ<14>
  VSS73  = GND
  DQ15_A  = M_A_CPU0_SA_DQ<15>
  VSS74  = GND
  DQ18_A  = M_A_CPU0_SA_DQ<18>
  VSS75  = GND
  DQ19_A  = M_A_CPU0_SA_DQ<19>
  VSS76  = GND
  \dqs7_a_c||tdqs7_a_c\  = M_A_CPU0_SA_DQS_DN<7>
  \dqs7_a_t||tdqs7_a_t\  = M_A_CPU0_SA_DQS_DP<7>
  VSS77  = GND
  DQ22_A  = M_A_CPU0_SA_DQ<22>
  VSS78  = GND
  DQ23_A  = M_A_CPU0_SA_DQ<23>
  VSS79  = GND
  DQ26_A  = M_A_CPU0_SA_DQ<26>
  VSS80  = GND
  DQ27_A  = M_A_CPU0_SA_DQ<27>
  VSS81  = GND
  \dqs8_a_c||tdqs8_a_c\  = M_A_CPU0_SA_DQS_DN<8>
  \dqs8_a_t||tdqs8_a_t\  = M_A_CPU0_SA_DQS_DP<8>
  VSS82  = GND
  DQ30_A  = M_A_CPU0_SA_DQ<30>
  VSS83  = GND
  DQ31_A  = M_A_CPU0_SA_DQ<31>
  VSS84  = GND
  CB2_A  = M_A_CPU0_SA_CB<2>
  VSS85  = GND
  CB3_A  = M_A_CPU0_SA_CB<3>
  VSS86  = GND
  \dqs9_a_c||tdqs9_a_c\  = M_A_CPU0_SA_DQS_DN<9>
  \dqs9_a_t||tdqs9_a_t\  = M_A_CPU0_SA_DQS_DP<9>
  VSS87  = GND
  CB6_A  = M_A_CPU0_SA_CB<6>
  VSS88  = GND
  CB7_A  = M_A_CPU0_SA_CB<7>
  VSS89  = GND
  RESET_N  = M_A_CPU0_RESET_N
  VSS90  = GND
  CS1_A_N  = M_A_CPU0_SA_CS_N<1>
  VSS91  = GND
  CA1_A  = M_A_CPU0_SA_CA<1>
  VSS92  = GND
  CA3_A  = M_A_CPU0_SA_CA<3>
  VSS93  = GND
  CA5_A  = M_A_CPU0_SA_CA<5>
  VSS94  = GND
  CK_T  = M_A_CPU0_CLK_DP<0>
  CK_C  = M_A_CPU0_CLK_DN<0>
  VSS95  = GND
  RFU4  = NC
  CA1_B  = M_A_CPU0_SB_CA<1>
  VSS96  = GND
  CA3_B  = M_A_CPU0_SB_CA<3>
  VSS97  = GND
  CA5_B  = M_A_CPU0_SB_CA<5>
  VSS98  = GND
  PAR_B  = M_A_CPU0_SB_PAR
  VSS99  = GND
  CS1_B_N  = M_A_CPU0_SB_CS_N<1>
  VSS100  = GND
  RFU5  = NC
  RFU6  = NC
  VSS101  = GND
  CB6_B  = M_A_CPU0_SB_CB<6>
  VSS102  = GND
  CB7_B  = M_A_CPU0_SB_CB<7>
  VSS103  = GND
  DQS4_B_C  = M_A_CPU0_SB_DQS_DN<4>
  DQS4_B_T  = M_A_CPU0_SB_DQS_DP<4>
  VSS104  = GND
  CB2_B  = M_A_CPU0_SB_CB<2>
  VSS105  = GND
  CB3_B  = M_A_CPU0_SB_CB<3>
  VSS106  = GND
  DQ2_B  = M_A_CPU0_SB_DQ<2>
  VSS107  = GND
  DQ3_B  = M_A_CPU0_SB_DQ<3>
  VSS108  = GND
  \dqs5_b_c||tdqs5_b_c\  = M_A_CPU0_SB_DQS_DN<5>
  \dqs5_b_t||tdqs5_b_t\  = M_A_CPU0_SB_DQS_DP<5>
  VSS109  = GND
  DQ6_B  = M_A_CPU0_SB_DQ<6>
  VSS110  = GND
  DQ7_B  = M_A_CPU0_SB_DQ<7>
  VSS111  = GND
  DQ10_B  = M_A_CPU0_SB_DQ<10>
  VSS112  = GND
  DQ11_B  = M_A_CPU0_SB_DQ<11>
  VSS113  = GND
  \dqs6_b_c||tdqs6_b_c\  = M_A_CPU0_SB_DQS_DN<6>
  \dqs6_b_t||tdqs6_b_t\  = M_A_CPU0_SB_DQS_DP<6>
  VSS114  = GND
  DQ14_B  = M_A_CPU0_SB_DQ<14>
  VSS115  = GND
  DQ15_B  = M_A_CPU0_SB_DQ<15>
  VSS116  = GND
  DQ18_B  = M_A_CPU0_SB_DQ<18>
  VSS117  = GND
  DQ19_B  = M_A_CPU0_SB_DQ<19>
  VSS118  = GND
  \dqs7_b_c||tdqs7_b_c\  = M_A_CPU0_SB_DQS_DN<7>
  \dqs7_b_t||tdqs7_b_t\  = M_A_CPU0_SB_DQS_DP<7>
  VSS119  = GND
  DQ22_B  = M_A_CPU0_SB_DQ<22>
  VSS120  = GND
  DQ23_B  = M_A_CPU0_SB_DQ<23>
  VSS121  = GND
  DQ26_B  = M_A_CPU0_SB_DQ<26>
  VSS122  = GND
  DQ27_B  = M_A_CPU0_SB_DQ<27>
  VSS123  = GND
  \dqs8_b_c||tdqs8_b_c\  = M_A_CPU0_SB_DQS_DN<8>
  \dqs8_b_t||tdqs8_b_t\  = M_A_CPU0_SB_DQS_DP<8>
  VSS124  = GND
  DQ30_B  = M_A_CPU0_SB_DQ<30>
  VSS125  = GND
  DQ31_B  = M_A_CPU0_SB_DQ<31>
  VSS126  = GND
  G1  = GND
  G2  = GND
  G3  = GND

(kicad_pcb
	(version 20260206)
	(generator "pcbnew")
	(generator_version "10.0")
	(general
		(thickness 1.6)
		(legacy_teardrops no)
	)
	(paper "A4")
	(title_block
		(title "04192023_DAF0TMB3IC0_F0TG_MB_C_brd_V02_OCP.brd")
		(comment 1 "Grand Teton / footprint 2352 of 8354 (J1), pads 185-230 of 291")
	)
	(layers
		(0 "F.Cu" signal "TOP")
		(4 "In1.Cu" signal "GND")
		(6 "In2.Cu" signal "IN1")
		(8 "In3.Cu" signal "GND1")
		(10 "In4.Cu" signal "IN2")
		(12 "In5.Cu" signal "GND2")
		(14 "In6.Cu" signal "IN3")
		(16 "In7.Cu" signal "GND3")
		(18 "In8.Cu" signal "VCC")
		(20 "In9.Cu" signal "VCC1")
		(22 "In10.Cu" signal "GND4")
		(24 "In11.Cu" signal "IN4")
		(26 "In12.Cu" signal "GND5")
		(28 "In13.Cu" signal "IN5")
		(30 "In14.Cu" signal "GND6")
		(32 "In15.Cu" signal "IN6")
		(34 "In16.Cu" signal "GND7")
		(2 "B.Cu" signal "BOTTOM")
		(9 "F.Adhes" user "F.Adhesive")
		(11 "B.Adhes" user "B.Adhesive")
		(13 "F.Paste" user "Package Geometry/Pastemask Top")
		(15 "B.Paste" user "Package Geometry/Pastemask Bottom")
		(5 "F.SilkS" user "Ref Des/Silkscreen Top")
		(7 "B.SilkS" user "Ref Des/Silkscreen Bottom")
		(1 "F.Mask" user "Board Geometry/Soldermask Top")
		(3 "B.Mask" user "Board Geometry/Soldermask Bottom")
		(17 "Dwgs.User" user "User.Drawings")
		(19 "Cmts.User" user "User.Comments")
		(21 "Eco1.User" user "User.Eco1")
		(23 "Eco2.User" user "User.Eco2")
		(25 "Edge.Cuts" user "Board Geometry/Outline")
		(27 "Margin" user)
		(31 "F.CrtYd" user "Package Geometry/Place Bound Top")
		(29 "B.CrtYd" user "Package Geometry/Place Bound Bottom")
		(35 "F.Fab" user "Ref Des/Assembly Top")
		(33 "B.Fab" user "Ref Des/Assembly Bottom")
	)
	(footprint ""
		(layer "F.Cu")
		(at 305.31816 -255.560068 180)
		(property "Reference" "J1"
			(at -2.2098 -81.984088 0)
			(unlocked yes)
			(layer "F.SilkS")
			(effects
				(font
					(size 0.7874 0.5842)
					(thickness 0.1524)
				)
			)
		)
		(property "Value" ""
			(at 0 0 180)
			(layer "F.Fab")
			(effects
				(font
					(size 1.27 1.27)
				)
			)
		)
		(duplicate_pad_numbers_are_jumpers no)
		(pad "185" smd rect
			(at 2.050034 -29.325062 90)
			(size 0.519938 1.4986)
			(layers "F.Cu" "F.Mask" "F.Paste")
			(net "M_A_CPU0_SA_DQ<26>")
		)
		(pad "186" smd rect
			(at 2.050034 -28.474924 90)
			(size 0.519938 1.4986)
			(layers "F.Cu" "F.Mask" "F.Paste")
			(net "GND")
		)
		(pad "187" smd rect
			(at 2.050034 -27.62504 90)
			(size 0.519938 1.4986)
			(layers "F.Cu" "F.Mask" "F.Paste")
			(net "M_A_CPU0_SA_DQ<27>")
		)
		(pad "188" smd rect
			(at 2.050034 -26.774902 90)
			(size 0.519938 1.4986)
			(layers "F.Cu" "F.Mask" "F.Paste")
			(net "GND")
		)
		(pad "189" smd rect
			(at 2.050034 -25.925018 90)
			(size 0.519938 1.4986)
			(layers "F.Cu" "F.Mask" "F.Paste")
			(net "M_A_CPU0_SA_DQS_DN<8>")
		)
		(pad "190" smd rect
			(at 2.050034 -25.07488 90)
			(size 0.519938 1.4986)
			(layers "F.Cu" "F.Mask" "F.Paste")
			(net "M_A_CPU0_SA_DQS_DP<8>")
		)
		(pad "191" smd rect
			(at 2.050034 -24.224996 90)
			(size 0.519938 1.4986)
			(layers "F.Cu" "F.Mask" "F.Paste")
			(net "GND")
		)
		(pad "192" smd rect
			(at 2.050034 -23.375112 90)
			(size 0.519938 1.4986)
			(layers "F.Cu" "F.Mask" "F.Paste")
			(net "M_A_CPU0_SA_DQ<30>")
		)
		(pad "193" smd rect
			(at 2.050034 -22.524974 90)
			(size 0.519938 1.4986)
			(layers "F.Cu" "F.Mask" "F.Paste")
			(net "GND")
		)
		(pad "194" smd rect
			(at 2.050034 -21.67509 90)
			(size 0.519938 1.4986)
			(layers "F.Cu" "F.Mask" "F.Paste")
			(net "M_A_CPU0_SA_DQ<31>")
		)
		(pad "195" smd rect
			(at 2.050034 -20.824952 90)
			(size 0.519938 1.4986)
			(layers "F.Cu" "F.Mask" "F.Paste")
			(net "GND")
		)
		(pad "196" smd rect
			(at 2.050034 -19.975068 90)
			(size 0.519938 1.4986)
			(layers "F.Cu" "F.Mask" "F.Paste")
			(net "M_A_CPU0_SA_CB<2>")
		)
		(pad "197" smd rect
			(at 2.050034 -19.12493 90)
			(size 0.519938 1.4986)
			(layers "F.Cu" "F.Mask" "F.Paste")
			(net "GND")
		)
		(pad "198" smd rect
			(at 2.050034 -18.275046 90)
			(size 0.519938 1.4986)
			(layers "F.Cu" "F.Mask" "F.Paste")
			(net "M_A_CPU0_SA_CB<3>")
		)
		(pad "199" smd rect
			(at 2.050034 -17.424908 90)
			(size 0.519938 1.4986)
			(layers "F.Cu" "F.Mask" "F.Paste")
			(net "GND")
		)
		(pad "200" smd rect
			(at 2.050034 -16.575024 90)
			(size 0.519938 1.4986)
			(layers "F.Cu" "F.Mask" "F.Paste")
			(net "M_A_CPU0_SA_DQS_DN<9>")
		)
		(pad "201" smd rect
			(at 2.050034 -15.724886 90)
			(size 0.519938 1.4986)
			(layers "F.Cu" "F.Mask" "F.Paste")
			(net "M_A_CPU0_SA_DQS_DP<9>")
		)
		(pad "202" smd rect
			(at 2.050034 -14.875002 90)
			(size 0.519938 1.4986)
			(layers "F.Cu" "F.Mask" "F.Paste")
			(net "GND")
		)
		(pad "203" smd rect
			(at 2.050034 -14.025118 90)
			(size 0.519938 1.4986)
			(layers "F.Cu" "F.Mask" "F.Paste")
			(net "M_A_CPU0_SA_CB<6>")
		)
		(pad "204" smd rect
			(at 2.050034 -13.17498 90)
			(size 0.519938 1.4986)
			(layers "F.Cu" "F.Mask" "F.Paste")
			(net "GND")
		)
		(pad "205" smd rect
			(at 2.050034 -12.325096 90)
			(size 0.519938 1.4986)
			(layers "F.Cu" "F.Mask" "F.Paste")
			(net "M_A_CPU0_SA_CB<7>")
		)
		(pad "206" smd rect
			(at 2.050034 -11.474958 90)
			(size 0.519938 1.4986)
			(layers "F.Cu" "F.Mask" "F.Paste")
			(net "GND")
		)
		(pad "207" smd rect
			(at 2.050034 -10.625074 90)
			(size 0.519938 1.4986)
			(layers "F.Cu" "F.Mask" "F.Paste")
			(net "M_A_CPU0_RESET_N")
		)
		(pad "208" smd rect
			(at 2.050034 -9.774936 90)
			(size 0.519938 1.4986)
			(layers "F.Cu" "F.Mask" "F.Paste")
			(net "GND")
		)
		(pad "209" smd rect
			(at 2.050034 -8.925052 90)
			(size 0.519938 1.4986)
			(layers "F.Cu" "F.Mask" "F.Paste")
			(net "M_A_CPU0_SA_CS_N<1>")
		)
		(pad "210" smd rect
			(at 2.050034 -8.074914 90)
			(size 0.519938 1.4986)
			(layers "F.Cu" "F.Mask" "F.Paste")
			(net "GND")
		)
		(pad "211" smd rect
			(at 2.050034 -7.22503 90)
			(size 0.519938 1.4986)
			(layers "F.Cu" "F.Mask" "F.Paste")
			(net "M_A_CPU0_SA_CA<1>")
		)
		(pad "212" smd rect
			(at 2.050034 -6.374892 90)
			(size 0.519938 1.4986)
			(layers "F.Cu" "F.Mask" "F.Paste")
			(net "GND")
		)
		(pad "213" smd rect
			(at 2.050034 -5.525008 90)
			(size 0.519938 1.4986)
			(layers "F.Cu" "F.Mask" "F.Paste")
			(net "M_A_CPU0_SA_CA<3>")
		)
		(pad "214" smd rect
			(at 2.050034 -4.675124 90)
			(size 0.519938 1.4986)
			(layers "F.Cu" "F.Mask" "F.Paste")
			(net "GND")
		)
		(pad "215" smd rect
			(at 2.050034 -3.824986 90)
			(size 0.519938 1.4986)
			(layers "F.Cu" "F.Mask" "F.Paste")
			(net "M_A_CPU0_SA_CA<5>")
		)
		(pad "216" smd rect
			(at 2.050034 -2.975102 90)
			(size 0.519938 1.4986)
			(layers "F.Cu" "F.Mask" "F.Paste")
			(net "GND")
		)
		(pad "217" smd rect
			(at 2.050034 -2.124964 90)
			(size 0.519938 1.4986)
			(layers "F.Cu" "F.Mask" "F.Paste")
			(net "M_A_CPU0_CLK_DP<0>")
		)
		(pad "218" smd rect
			(at 2.050034 -1.27508 90)
			(size 0.519938 1.4986)
			(layers "F.Cu" "F.Mask" "F.Paste")
			(net "M_A_CPU0_CLK_DN<0>")
		)
		(pad "219" smd rect
			(at 2.050034 -0.424942 90)
			(size 0.519938 1.4986)
			(layers "F.Cu" "F.Mask" "F.Paste")
			(net "GND")
		)
		(pad "220" smd rect
			(at 2.050034 5.525008 90)
			(size 0.519938 1.4986)
			(layers "F.Cu" "F.Mask" "F.Paste")
			(net "Net_2253")
		)
		(pad "221" smd rect
			(at 2.050034 6.374892 90)
			(size 0.519938 1.4986)
			(layers "F.Cu" "F.Mask" "F.Paste")
			(net "M_A_CPU0_SB_CA<1>")
		)
		(pad "222" smd rect
			(at 2.050034 7.22503 90)
			(size 0.519938 1.4986)
			(layers "F.Cu" "F.Mask" "F.Paste")
			(net "GND")
		)
		(pad "223" smd rect
			(at 2.050034 8.074914 90)
			(size 0.519938 1.4986)
			(layers "F.Cu" "F.Mask" "F.Paste")
			(net "M_A_CPU0_SB_CA<3>")
		)
		(pad "224" smd rect
			(at 2.050034 8.925052 90)
			(size 0.519938 1.4986)
			(layers "F.Cu" "F.Mask" "F.Paste")
			(net "GND")
		)
		(pad "225" smd rect
			(at 2.050034 9.774936 90)
			(size 0.519938 1.4986)
			(layers "F.Cu" "F.Mask" "F.Paste")
			(net "M_A_CPU0_SB_CA<5>")
		)
		(pad "226" smd rect
			(at 2.050034 10.625074 90)
			(size 0.519938 1.4986)
			(layers "F.Cu" "F.Mask" "F.Paste")
			(net "GND")
		)
		(pad "227" smd rect
			(at 2.050034 11.474958 90)
			(size 0.519938 1.4986)
			(layers "F.Cu" "F.Mask" "F.Paste")
			(net "M_A_CPU0_SB_PAR")
		)
		(pad "228" smd rect
			(at 2.050034 12.325096 90)
			(size 0.519938 1.4986)
			(layers "F.Cu" "F.Mask" "F.Paste")
			(net "GND")
		)
		(pad "229" smd rect
			(at 2.050034 13.17498 90)
			(size 0.519938 1.4986)
			(layers "F.Cu" "F.Mask" "F.Paste")
			(net "M_A_CPU0_SB_CS_N<1>")
		)
		(pad "230" smd rect
			(at 2.050034 14.025118 90)
			(size 0.519938 1.4986)
			(layers "F.Cu" "F.Mask" "F.Paste")
			(net "GND")
		)
	)
)
